(kicad_sch (version 20230121) (generator eeschema)

  (paper "A3")

  (title_block
    (title "D1600E PSU Breakout Board")
    (date "2023-10-18")
    (rev "1.4.3")
    (comment 1 "www.antmicro.com")
    (comment 2 "Antmicro Ltd.")
  )

  (junction (at 176.53 127) (diameter 0) (color 0 0 0 0)
  )
  (junction (at 176.53 167.64) (diameter 0) (color 0 0 0 0)
  )
  (junction (at 185.42 116.84) (diameter 0) (color 0 0 0 0)
  )
  (junction (at 185.42 167.64) (diameter 0) (color 0 0 0 0)
  )
  (junction (at 194.31 167.64) (diameter 0) (color 0 0 0 0)
  )
  (junction (at 284.48 151.13) (diameter 0) (color 0 0 0 0)
  )
  (junction (at 284.48 156.21) (diameter 0) (color 0 0 0 0)
  )
  (junction (at 124.46 167.64) (diameter 0) (color 0 0 0 0)
  )
  (junction (at 166.37 167.64) (diameter 0) (color 0 0 0 0)
  )
  (junction (at 261.62 148.59) (diameter 0) (color 0 0 0 0)
  )
  (junction (at 194.31 116.84) (diameter 0) (color 0 0 0 0)
  )
  (junction (at 176.53 177.8) (diameter 0) (color 0 0 0 0)
  )
  (junction (at 261.62 158.75) (diameter 0) (color 0 0 0 0)
  )
  (junction (at 289.56 153.67) (diameter 0) (color 0 0 0 0)
  )
  (junction (at 176.53 116.84) (diameter 0) (color 0 0 0 0)
  )
  (junction (at 124.46 116.84) (diameter 0) (color 0 0 0 0)
  )
  (junction (at 166.37 116.84) (diameter 0) (color 0 0 0 0)
  )

  (no_connect (at 133.35 172.72))
  (no_connect (at 133.35 121.92))

  (wire (pts (xy 261.62 148.59) (xy 262.89 148.59))
    (stroke (width 0) (type default))
  )
  (wire (pts (xy 132.08 138.43) (xy 132.08 127))
    (stroke (width 0) (type default))
  )
  (wire (pts (xy 132.08 127) (xy 133.35 127))
    (stroke (width 0) (type default))
  )
  (wire (pts (xy 153.67 121.92) (xy 156.21 121.92))
    (stroke (width 0) (type default))
  )
  (wire (pts (xy 173.99 116.84) (xy 176.53 116.84))
    (stroke (width 0) (type default))
  )
  (wire (pts (xy 194.31 167.64) (xy 198.12 167.64))
    (stroke (width 0) (type default))
  )
  (wire (pts (xy 124.46 167.64) (xy 133.35 167.64))
    (stroke (width 0) (type default))
  )
  (wire (pts (xy 153.67 172.72) (xy 156.21 172.72))
    (stroke (width 0) (type default))
  )
  (wire (pts (xy 153.67 116.84) (xy 166.37 116.84))
    (stroke (width 0) (type default))
  )
  (wire (pts (xy 185.42 167.64) (xy 194.31 167.64))
    (stroke (width 0) (type default))
  )
  (wire (pts (xy 194.31 116.84) (xy 194.31 125.73))
    (stroke (width 0) (type default))
  )
  (wire (pts (xy 261.62 158.75) (xy 262.89 158.75))
    (stroke (width 0) (type default))
  )
  (wire (pts (xy 275.59 151.13) (xy 284.48 151.13))
    (stroke (width 0) (type default))
  )
  (wire (pts (xy 276.86 162.56) (xy 261.62 162.56))
    (stroke (width 0) (type default))
  )
  (wire (pts (xy 289.56 153.67) (xy 289.56 156.21))
    (stroke (width 0) (type default))
  )
  (wire (pts (xy 176.53 186.69) (xy 176.53 189.23))
    (stroke (width 0) (type default))
  )
  (wire (pts (xy 166.37 167.64) (xy 166.37 172.72))
    (stroke (width 0) (type default))
  )
  (wire (pts (xy 255.27 158.75) (xy 261.62 158.75))
    (stroke (width 0) (type default))
  )
  (wire (pts (xy 161.29 121.92) (xy 166.37 121.92))
    (stroke (width 0) (type default))
  )
  (wire (pts (xy 132.08 189.23) (xy 132.08 177.8))
    (stroke (width 0) (type default))
  )
  (wire (pts (xy 161.29 172.72) (xy 166.37 172.72))
    (stroke (width 0) (type default))
  )
  (wire (pts (xy 284.48 151.13) (xy 284.48 156.21))
    (stroke (width 0) (type default))
  )
  (wire (pts (xy 194.31 116.84) (xy 198.12 116.84))
    (stroke (width 0) (type default))
  )
  (wire (pts (xy 261.62 148.59) (xy 261.62 151.13))
    (stroke (width 0) (type default))
  )
  (wire (pts (xy 185.42 167.64) (xy 185.42 176.53))
    (stroke (width 0) (type default))
  )
  (wire (pts (xy 255.27 153.67) (xy 262.89 153.67))
    (stroke (width 0) (type default))
  )
  (wire (pts (xy 284.48 151.13) (xy 284.48 148.59))
    (stroke (width 0) (type default))
  )
  (wire (pts (xy 124.46 116.84) (xy 133.35 116.84))
    (stroke (width 0) (type default))
  )
  (wire (pts (xy 166.37 167.64) (xy 168.91 167.64))
    (stroke (width 0) (type default))
  )
  (wire (pts (xy 275.59 156.21) (xy 284.48 156.21))
    (stroke (width 0) (type default))
  )
  (wire (pts (xy 259.08 165.1) (xy 259.08 156.21))
    (stroke (width 0) (type default))
  )
  (wire (pts (xy 176.53 177.8) (xy 176.53 181.61))
    (stroke (width 0) (type default))
  )
  (wire (pts (xy 176.53 127) (xy 176.53 130.81))
    (stroke (width 0) (type default))
  )
  (wire (pts (xy 295.91 151.13) (xy 298.45 151.13))
    (stroke (width 0) (type default))
  )
  (wire (pts (xy 124.46 130.81) (xy 124.46 138.43))
    (stroke (width 0) (type default))
  )
  (wire (pts (xy 124.46 167.64) (xy 124.46 176.53))
    (stroke (width 0) (type default))
  )
  (wire (pts (xy 194.31 130.81) (xy 194.31 138.43))
    (stroke (width 0) (type default))
  )
  (wire (pts (xy 276.86 158.75) (xy 276.86 162.56))
    (stroke (width 0) (type default))
  )
  (wire (pts (xy 259.08 156.21) (xy 262.89 156.21))
    (stroke (width 0) (type default))
  )
  (wire (pts (xy 289.56 153.67) (xy 298.45 153.67))
    (stroke (width 0) (type default))
  )
  (wire (pts (xy 185.42 130.81) (xy 185.42 138.43))
    (stroke (width 0) (type default))
  )
  (wire (pts (xy 176.53 167.64) (xy 176.53 170.18))
    (stroke (width 0) (type default))
  )
  (wire (pts (xy 173.99 167.64) (xy 176.53 167.64))
    (stroke (width 0) (type default))
  )
  (wire (pts (xy 185.42 116.84) (xy 194.31 116.84))
    (stroke (width 0) (type default))
  )
  (wire (pts (xy 120.65 167.64) (xy 124.46 167.64))
    (stroke (width 0) (type default))
  )
  (wire (pts (xy 153.67 127) (xy 176.53 127))
    (stroke (width 0) (type default))
  )
  (wire (pts (xy 124.46 181.61) (xy 124.46 189.23))
    (stroke (width 0) (type default))
  )
  (wire (pts (xy 120.65 116.84) (xy 124.46 116.84))
    (stroke (width 0) (type default))
  )
  (wire (pts (xy 176.53 116.84) (xy 176.53 119.38))
    (stroke (width 0) (type default))
  )
  (wire (pts (xy 297.18 156.21) (xy 297.18 165.1))
    (stroke (width 0) (type default))
  )
  (wire (pts (xy 176.53 167.64) (xy 185.42 167.64))
    (stroke (width 0) (type default))
  )
  (wire (pts (xy 261.62 158.75) (xy 261.62 162.56))
    (stroke (width 0) (type default))
  )
  (wire (pts (xy 124.46 116.84) (xy 124.46 125.73))
    (stroke (width 0) (type default))
  )
  (wire (pts (xy 166.37 116.84) (xy 168.91 116.84))
    (stroke (width 0) (type default))
  )
  (wire (pts (xy 297.18 156.21) (xy 298.45 156.21))
    (stroke (width 0) (type default))
  )
  (wire (pts (xy 153.67 177.8) (xy 176.53 177.8))
    (stroke (width 0) (type default))
  )
  (wire (pts (xy 176.53 135.89) (xy 176.53 138.43))
    (stroke (width 0) (type default))
  )
  (wire (pts (xy 176.53 175.26) (xy 176.53 177.8))
    (stroke (width 0) (type default))
  )
  (wire (pts (xy 284.48 156.21) (xy 284.48 165.1))
    (stroke (width 0) (type default))
  )
  (wire (pts (xy 194.31 167.64) (xy 194.31 176.53))
    (stroke (width 0) (type default))
  )
  (wire (pts (xy 262.89 151.13) (xy 261.62 151.13))
    (stroke (width 0) (type default))
  )
  (wire (pts (xy 185.42 181.61) (xy 185.42 189.23))
    (stroke (width 0) (type default))
  )
  (wire (pts (xy 176.53 127) (xy 176.53 124.46))
    (stroke (width 0) (type default))
  )
  (wire (pts (xy 255.27 148.59) (xy 261.62 148.59))
    (stroke (width 0) (type default))
  )
  (wire (pts (xy 166.37 121.92) (xy 166.37 116.84))
    (stroke (width 0) (type default))
  )
  (wire (pts (xy 185.42 116.84) (xy 185.42 125.73))
    (stroke (width 0) (type default))
  )
  (wire (pts (xy 276.86 158.75) (xy 275.59 158.75))
    (stroke (width 0) (type default))
  )
  (wire (pts (xy 275.59 148.59) (xy 284.48 148.59))
    (stroke (width 0) (type default))
  )
  (wire (pts (xy 275.59 153.67) (xy 289.56 153.67))
    (stroke (width 0) (type default))
  )
  (wire (pts (xy 132.08 177.8) (xy 133.35 177.8))
    (stroke (width 0) (type default))
  )
  (wire (pts (xy 176.53 116.84) (xy 185.42 116.84))
    (stroke (width 0) (type default))
  )
  (wire (pts (xy 194.31 181.61) (xy 194.31 189.23))
    (stroke (width 0) (type default))
  )
  (wire (pts (xy 153.67 167.64) (xy 166.37 167.64))
    (stroke (width 0) (type default))
  )

  (rectangle (start 100.33 157.48) (end 220.98 198.12)
    (stroke (width 0) (type default))
    (fill (type none))
  )
  (rectangle (start 242.57 139.7) (end 317.5 171.45)
    (stroke (width 0) (type default))
    (fill (type none))
  )
  (rectangle (start 100.33 106.68) (end 220.98 147.32)
    (stroke (width 0) (type default))
    (fill (type none))
  )

  (text "Daughterboard power connector" (at 242.57 138.43 0)
    (effects (font (size 2.9972 2.9972)) (justify left bottom))
  )
  (text "3V3 DC/DC Converter" (at 100.33 156.21 0)
    (effects (font (size 2.9972 2.9972)) (justify left bottom))
  )
  (text "EN floating for \nauto startup\n" (at 135.89 134.62 0)
    (effects (font (size 1.27 1.27)) (justify left bottom))
  )
  (text "5V0 DC/DC Converter" (at 100.33 105.41 0)
    (effects (font (size 2.9972 2.9972)) (justify left bottom))
  )

  (global_label "VCC3V3" (shape input) (at 198.12 167.64 0) (fields_autoplaced)
    (effects (font (size 1.27 1.27)) (justify left))
    (property "Intersheetrefs" "${INTERSHEET_REFS}" (at 48.895 66.04 0)
      (effects (font (size 1.27 1.27)) hide)
    )
  )
  (global_label "VCC12V0" (shape input) (at 120.65 167.64 180) (fields_autoplaced)
    (effects (font (size 1.4986 1.4986)) (justify right))
    (property "Intersheetrefs" "${INTERSHEET_REFS}" (at 65.405 66.04 0)
      (effects (font (size 1.27 1.27)) hide)
    )
  )
  (global_label "VCC5V0" (shape input) (at 198.12 116.84 0) (fields_autoplaced)
    (effects (font (size 1.27 1.27)) (justify left))
    (property "Intersheetrefs" "${INTERSHEET_REFS}" (at 48.26 71.12 0)
      (effects (font (size 1.27 1.27)) hide)
    )
  )
  (global_label "VCC5V0" (shape input) (at 255.27 153.67 180) (fields_autoplaced)
    (effects (font (size 1.27 1.27)) (justify right))
    (property "Intersheetrefs" "${INTERSHEET_REFS}" (at 21.59 96.52 0)
      (effects (font (size 1.27 1.27)) hide)
    )
  )
  (global_label "VCC12V0" (shape input) (at 120.65 116.84 180) (fields_autoplaced)
    (effects (font (size 1.4986 1.4986)) (justify right))
    (property "Intersheetrefs" "${INTERSHEET_REFS}" (at 65.405 71.12 0)
      (effects (font (size 1.27 1.27)) hide)
    )
  )
  (global_label "VCC3V3" (shape input) (at 255.27 158.75 180) (fields_autoplaced)
    (effects (font (size 1.27 1.27)) (justify right))
    (property "Intersheetrefs" "${INTERSHEET_REFS}" (at 21.59 109.22 0)
      (effects (font (size 1.27 1.27)) hide)
    )
  )
  (global_label "VCC12V0" (shape input) (at 255.27 148.59 180) (fields_autoplaced)
    (effects (font (size 1.27 1.27)) (justify right))
    (property "Intersheetrefs" "${INTERSHEET_REFS}" (at 21.59 95.25 0)
      (effects (font (size 1.27 1.27)) hide)
    )
  )
  (global_label "VCC5V0" (shape input) (at 295.91 151.13 180) (fields_autoplaced)
    (effects (font (size 1.27 1.27)) (justify right))
    (property "Intersheetrefs" "${INTERSHEET_REFS}" (at 62.23 93.98 0)
      (effects (font (size 1.27 1.27)) hide)
    )
  )

  (symbol (lib_name "AP62301_TSOT_1") (lib_id "antmicroDCDCConverters:AP62301_TSOT") (at 133.35 116.84 0) (unit 1)
    (in_bom yes) (on_board yes) (dnp no) (fields_autoplaced)
    (property "Reference" "U15" (at 143.51 109.22 0)
      (effects (font (size 1.27 1.27)))
    )
    (property "Value" "AP62301_TSOT" (at 168.91 124.46 0)
      (effects (font (size 1.27 1.27) (thickness 0.15)) (justify left bottom) hide)
    )
    (property "Footprint" "antmicro-footprints:TSOT23-6" (at 168.91 127 0)
      (effects (font (size 1.27 1.27) (thickness 0.15)) (justify left bottom) hide)
    )
    (property "Datasheet" "https://www.diodes.com/assets/Datasheets/AP62300_AP62301_AP62300T.pdf" (at 168.91 129.54 0)
      (effects (font (size 1.27 1.27) (thickness 0.15)) (justify left bottom) hide)
    )
    (property "MPN" "AP62301WU-7" (at 143.51 111.76 0)
      (effects (font (size 1.27 1.27) (thickness 0.15)))
    )
    (property "Manufacturer" "Diodes Incorporated" (at 168.91 132.08 0)
      (effects (font (size 1.27 1.27) (thickness 0.15)) (justify left bottom) hide)
    )
    (property "Author" "Antmicro" (at 168.91 134.62 0)
      (effects (font (size 1.27 1.27) (thickness 0.15)) (justify left bottom) hide)
    )
    (property "License" "Apache-2.0" (at 168.91 137.16 0)
      (effects (font (size 1.27 1.27) (thickness 0.15)) (justify left bottom) hide)
    )
    (pin "1")
    (pin "2")
    (pin "3")
    (pin "4")
    (pin "5")
    (pin "6")
    (instances
      (project "d1600e-psu-breakout-board"
        (path ""
          (reference "U15") (unit 1)
        )
      )
    )
  )

  (symbol (lib_name "L_3u3_4.1A_WE-LHMI-5030_1") (lib_id "antmicroFixedInductors:L_3u3_4.1A_WE-LHMI-5030") (at 168.91 116.84 0) (unit 1)
    (in_bom yes) (on_board yes) (dnp no) (fields_autoplaced)
    (property "Reference" "L2" (at 171.45 111.76 0)
      (effects (font (size 1.27 1.27)))
    )
    (property "Value" "L_3u3_4.1A_WE-LHMI-5030" (at 182.88 119.38 0)
      (effects (font (size 1.27 1.27) (thickness 0.15)) (justify left bottom) hide)
    )
    (property "Footprint" "antmicro-footprints:L_WE-LHMI-5030" (at 182.88 124.46 0)
      (effects (font (size 1.27 1.27) (thickness 0.15)) (justify left bottom) hide)
    )
    (property "Datasheet" "https://www.we-online.com/catalog/datasheet/74437336033.pdf" (at 182.88 127 0)
      (effects (font (size 1.27 1.27) (thickness 0.15)) (justify left bottom) hide)
    )
    (property "Manufacturer" "Würth Elektronik" (at 182.88 129.54 0)
      (effects (font (size 1.27 1.27) (thickness 0.15)) (justify left bottom) hide)
    )
    (property "MPN" "74437336033" (at 182.88 132.08 0)
      (effects (font (size 1.27 1.27) (thickness 0.15)) (justify left bottom) hide)
    )
    (property "Val" "3u3/4.1A" (at 171.45 114.3 0)
      (effects (font (size 1.27 1.27) (thickness 0.15)))
    )
    (property "Size" "5.2x5.2" (at 182.88 139.7 0)
      (effects (font (size 1.27 1.27) (thickness 0.15)) (justify left bottom) hide)
    )
    (property "ISat" "5.45A" (at 182.88 133.35 0)
      (effects (font (size 1.27 1.27)) (justify left) hide)
    )
    (property "IMax" "4.1A" (at 182.88 137.16 0)
      (effects (font (size 1.27 1.27) (thickness 0.15)) (justify left bottom) hide)
    )
    (property "Author" "Antmicro" (at 182.88 142.24 0)
      (effects (font (size 1.27 1.27) (thickness 0.15)) (justify left bottom) hide)
    )
    (property "License" "Apache-2.0" (at 182.88 144.78 0)
      (effects (font (size 1.27 1.27) (thickness 0.15)) (justify left bottom) hide)
    )
    (pin "1")
    (pin "2")
    (instances
      (project "d1600e-psu-breakout-board"
        (path ""
          (reference "L2") (unit 1)
        )
      )
    )
  )

  (symbol (lib_name "C_100n_0402_1") (lib_id "antmicroCapacitors0402:C_100n_0402") (at 156.21 121.92 0) (unit 1)
    (in_bom yes) (on_board yes) (dnp no)
    (property "Reference" "C25" (at 160.02 120.65 0)
      (effects (font (size 1.27 1.27)) (justify left))
    )
    (property "Value" "C_100n_0402" (at 176.53 132.08 0)
      (effects (font (size 1.27 1.27) (thickness 0.15)) (justify left bottom) hide)
    )
    (property "Footprint" "antmicro-footprints:C_0402_1005Metric" (at 176.53 134.62 0)
      (effects (font (size 1.27 1.27) (thickness 0.15)) (justify left bottom) hide)
    )
    (property "Datasheet" "https://www.murata.com/products/productdetail?partno=GRM155R61H104KE14%23" (at 176.53 137.16 0)
      (effects (font (size 1.27 1.27) (thickness 0.15)) (justify left bottom) hide)
    )
    (property "Manufacturer" "Murata" (at 176.53 142.24 0)
      (effects (font (size 1.27 1.27) (thickness 0.15)) (justify left bottom) hide)
    )
    (property "MPN" "GRM155R61H104KE14D" (at 176.53 139.7 0)
      (effects (font (size 1.27 1.27) (thickness 0.15)) (justify left bottom) hide)
    )
    (property "Val" "100n" (at 162.56 123.19 0)
      (effects (font (size 1.27 1.27) (thickness 0.15)))
    )
    (property "License" "Apache-2.0" (at 176.53 144.78 0)
      (effects (font (size 1.27 1.27) (thickness 0.15)) (justify left bottom) hide)
    )
    (property "Author" "Antmicro" (at 176.53 147.32 0)
      (effects (font (size 1.27 1.27) (thickness 0.15)) (justify left bottom) hide)
    )
    (property "Voltage" "50V" (at 176.53 149.86 0)
      (effects (font (size 1.27 1.27)) (justify left bottom) hide)
    )
    (property "Dielectric" "X5R" (at 176.53 152.4 0)
      (effects (font (size 1.27 1.27)) (justify left bottom) hide)
    )
    (pin "1")
    (pin "2")
    (instances
      (project "d1600e-psu-breakout-board"
        (path ""
          (reference "C25") (unit 1)
        )
      )
    )
  )

  (symbol (lib_id "antmicropower:GND") (at 176.53 138.43 0) (unit 1)
    (in_bom yes) (on_board yes) (dnp no)
    (property "Reference" "#PWR063" (at 176.53 144.78 0)
      (effects (font (size 1.27 1.27)) hide)
    )
    (property "Value" "GND" (at 176.53 142.24 0)
      (effects (font (size 1.27 1.27) (thickness 0.15)))
    )
    (property "Footprint" "" (at 185.42 146.05 0)
      (effects (font (size 1.27 1.27) (thickness 0.15)) (justify left bottom) hide)
    )
    (property "Datasheet" "" (at 185.42 151.13 0)
      (effects (font (size 1.27 1.27) (thickness 0.15)) (justify left bottom) hide)
    )
    (property "Author" "Antmicro" (at 185.42 146.05 0)
      (effects (font (size 1.27 1.27) (thickness 0.15)) (justify left bottom) hide)
    )
    (property "License" "Apache-2.0" (at 185.42 148.59 0)
      (effects (font (size 1.27 1.27) (thickness 0.15)) (justify left bottom) hide)
    )
    (pin "1")
    (instances
      (project "d1600e-psu-breakout-board"
        (path ""
          (reference "#PWR063") (unit 1)
        )
      )
    )
  )

  (symbol (lib_id "antmicropower:GND") (at 132.08 138.43 0) (unit 1)
    (in_bom yes) (on_board yes) (dnp no)
    (property "Reference" "#PWR062" (at 132.08 144.78 0)
      (effects (font (size 1.27 1.27)) hide)
    )
    (property "Value" "GND" (at 132.08 142.24 0)
      (effects (font (size 1.27 1.27) (thickness 0.15)))
    )
    (property "Footprint" "" (at 140.97 146.05 0)
      (effects (font (size 1.27 1.27) (thickness 0.15)) (justify left bottom) hide)
    )
    (property "Datasheet" "" (at 140.97 151.13 0)
      (effects (font (size 1.27 1.27) (thickness 0.15)) (justify left bottom) hide)
    )
    (property "Author" "Antmicro" (at 140.97 146.05 0)
      (effects (font (size 1.27 1.27) (thickness 0.15)) (justify left bottom) hide)
    )
    (property "License" "Apache-2.0" (at 140.97 148.59 0)
      (effects (font (size 1.27 1.27) (thickness 0.15)) (justify left bottom) hide)
    )
    (pin "1")
    (instances
      (project "d1600e-psu-breakout-board"
        (path ""
          (reference "#PWR062") (unit 1)
        )
      )
    )
  )

  (symbol (lib_name "C_22u_0603_1") (lib_id "antmicroCapacitors0603:C_22u_0603") (at 185.42 130.81 90) (unit 1)
    (in_bom yes) (on_board yes) (dnp no)
    (property "Reference" "C26" (at 186.055 126.365 90)
      (effects (font (size 1.27 1.27)) (justify right))
    )
    (property "Value" "C_22u_0603" (at 195.58 110.49 0)
      (effects (font (size 1.27 1.27) (thickness 0.15)) (justify left bottom) hide)
    )
    (property "Footprint" "antmicro-footprints:C_0603_1608Metric" (at 198.12 110.49 0)
      (effects (font (size 1.27 1.27) (thickness 0.15)) (justify left bottom) hide)
    )
    (property "Datasheet" "https://www.murata.com/products/productdetail?partno=GRM188R60J226MEA0%23" (at 200.66 110.49 0)
      (effects (font (size 1.27 1.27) (thickness 0.15)) (justify left bottom) hide)
    )
    (property "Manufacturer" "Murata" (at 205.74 110.49 0)
      (effects (font (size 1.27 1.27) (thickness 0.15)) (justify left bottom) hide)
    )
    (property "MPN" "GRM188R60J226MEA0D" (at 203.2 110.49 0)
      (effects (font (size 1.27 1.27) (thickness 0.15)) (justify left bottom) hide)
    )
    (property "Val" "22u" (at 186.055 130.175 90)
      (effects (font (size 1.27 1.27) (thickness 0.15)) (justify right))
    )
    (property "License" "Apache-2.0" (at 208.28 110.49 0)
      (effects (font (size 1.27 1.27) (thickness 0.15)) (justify left bottom) hide)
    )
    (property "Author" "Antmicro" (at 210.82 110.49 0)
      (effects (font (size 1.27 1.27) (thickness 0.15)) (justify left bottom) hide)
    )
    (property "Voltage" "" (at 213.36 110.49 0)
      (effects (font (size 1.27 1.27)) (justify left bottom) hide)
    )
    (property "Dielectric" "" (at 215.9 110.49 0)
      (effects (font (size 1.27 1.27)) (justify left bottom) hide)
    )
    (pin "1")
    (pin "2")
    (instances
      (project "d1600e-psu-breakout-board"
        (path ""
          (reference "C26") (unit 1)
        )
      )
    )
  )

  (symbol (lib_name "C_22u_0603_2") (lib_id "antmicroCapacitors0603:C_22u_0603") (at 194.31 130.81 90) (unit 1)
    (in_bom yes) (on_board yes) (dnp no)
    (property "Reference" "C27" (at 194.945 126.365 90)
      (effects (font (size 1.27 1.27)) (justify right))
    )
    (property "Value" "C_22u_0603" (at 204.47 110.49 0)
      (effects (font (size 1.27 1.27) (thickness 0.15)) (justify left bottom) hide)
    )
    (property "Footprint" "antmicro-footprints:C_0603_1608Metric" (at 207.01 110.49 0)
      (effects (font (size 1.27 1.27) (thickness 0.15)) (justify left bottom) hide)
    )
    (property "Datasheet" "https://www.murata.com/products/productdetail?partno=GRM188R60J226MEA0%23" (at 209.55 110.49 0)
      (effects (font (size 1.27 1.27) (thickness 0.15)) (justify left bottom) hide)
    )
    (property "Manufacturer" "Murata" (at 214.63 110.49 0)
      (effects (font (size 1.27 1.27) (thickness 0.15)) (justify left bottom) hide)
    )
    (property "MPN" "GRM188R60J226MEA0D" (at 212.09 110.49 0)
      (effects (font (size 1.27 1.27) (thickness 0.15)) (justify left bottom) hide)
    )
    (property "Val" "22u" (at 194.945 130.175 90)
      (effects (font (size 1.27 1.27) (thickness 0.15)) (justify right))
    )
    (property "License" "Apache-2.0" (at 217.17 110.49 0)
      (effects (font (size 1.27 1.27) (thickness 0.15)) (justify left bottom) hide)
    )
    (property "Author" "Antmicro" (at 219.71 110.49 0)
      (effects (font (size 1.27 1.27) (thickness 0.15)) (justify left bottom) hide)
    )
    (property "Voltage" "" (at 222.25 110.49 0)
      (effects (font (size 1.27 1.27)) (justify left bottom) hide)
    )
    (property "Dielectric" "" (at 224.79 110.49 0)
      (effects (font (size 1.27 1.27)) (justify left bottom) hide)
    )
    (pin "1")
    (pin "2")
    (instances
      (project "d1600e-psu-breakout-board"
        (path ""
          (reference "C27") (unit 1)
        )
      )
    )
  )

  (symbol (lib_id "antmicropower:GND") (at 124.46 138.43 0) (unit 1)
    (in_bom yes) (on_board yes) (dnp no)
    (property "Reference" "#PWR061" (at 124.46 144.78 0)
      (effects (font (size 1.27 1.27)) hide)
    )
    (property "Value" "GND" (at 124.46 142.24 0)
      (effects (font (size 1.27 1.27) (thickness 0.15)))
    )
    (property "Footprint" "" (at 133.35 146.05 0)
      (effects (font (size 1.27 1.27) (thickness 0.15)) (justify left bottom) hide)
    )
    (property "Datasheet" "" (at 133.35 151.13 0)
      (effects (font (size 1.27 1.27) (thickness 0.15)) (justify left bottom) hide)
    )
    (property "Author" "Antmicro" (at 133.35 146.05 0)
      (effects (font (size 1.27 1.27) (thickness 0.15)) (justify left bottom) hide)
    )
    (property "License" "Apache-2.0" (at 133.35 148.59 0)
      (effects (font (size 1.27 1.27) (thickness 0.15)) (justify left bottom) hide)
    )
    (pin "1")
    (instances
      (project "d1600e-psu-breakout-board"
        (path ""
          (reference "#PWR061") (unit 1)
        )
      )
    )
  )

  (symbol (lib_id "antmicropower:GND") (at 185.42 138.43 0) (unit 1)
    (in_bom yes) (on_board yes) (dnp no)
    (property "Reference" "#PWR064" (at 185.42 144.78 0)
      (effects (font (size 1.27 1.27)) hide)
    )
    (property "Value" "GND" (at 185.42 142.24 0)
      (effects (font (size 1.27 1.27) (thickness 0.15)))
    )
    (property "Footprint" "" (at 194.31 146.05 0)
      (effects (font (size 1.27 1.27) (thickness 0.15)) (justify left bottom) hide)
    )
    (property "Datasheet" "" (at 194.31 151.13 0)
      (effects (font (size 1.27 1.27) (thickness 0.15)) (justify left bottom) hide)
    )
    (property "Author" "Antmicro" (at 194.31 146.05 0)
      (effects (font (size 1.27 1.27) (thickness 0.15)) (justify left bottom) hide)
    )
    (property "License" "Apache-2.0" (at 194.31 148.59 0)
      (effects (font (size 1.27 1.27) (thickness 0.15)) (justify left bottom) hide)
    )
    (pin "1")
    (instances
      (project "d1600e-psu-breakout-board"
        (path ""
          (reference "#PWR064") (unit 1)
        )
      )
    )
  )

  (symbol (lib_id "antmicropower:GND") (at 194.31 138.43 0) (unit 1)
    (in_bom yes) (on_board yes) (dnp no)
    (property "Reference" "#PWR065" (at 194.31 144.78 0)
      (effects (font (size 1.27 1.27)) hide)
    )
    (property "Value" "GND" (at 194.31 142.24 0)
      (effects (font (size 1.27 1.27) (thickness 0.15)))
    )
    (property "Footprint" "" (at 203.2 146.05 0)
      (effects (font (size 1.27 1.27) (thickness 0.15)) (justify left bottom) hide)
    )
    (property "Datasheet" "" (at 203.2 151.13 0)
      (effects (font (size 1.27 1.27) (thickness 0.15)) (justify left bottom) hide)
    )
    (property "Author" "Antmicro" (at 203.2 146.05 0)
      (effects (font (size 1.27 1.27) (thickness 0.15)) (justify left bottom) hide)
    )
    (property "License" "Apache-2.0" (at 203.2 148.59 0)
      (effects (font (size 1.27 1.27) (thickness 0.15)) (justify left bottom) hide)
    )
    (pin "1")
    (instances
      (project "d1600e-psu-breakout-board"
        (path ""
          (reference "#PWR065") (unit 1)
        )
      )
    )
  )

  (symbol (lib_name "C_10u_25V_0603_1") (lib_id "antmicroCapacitors0603:C_10u_25V_0603") (at 124.46 130.81 90) (unit 1)
    (in_bom yes) (on_board yes) (dnp no)
    (property "Reference" "C24" (at 125.095 126.365 90)
      (effects (font (size 1.27 1.27)) (justify right))
    )
    (property "Value" "C_10u_25V_0603" (at 134.62 110.49 0)
      (effects (font (size 1.27 1.27) (thickness 0.15)) (justify left bottom) hide)
    )
    (property "Footprint" "antmicro-footprints:C_0603_1608Metric" (at 137.16 110.49 0)
      (effects (font (size 1.27 1.27) (thickness 0.15)) (justify left bottom) hide)
    )
    (property "Datasheet" "https://product.tdk.com/en/search/capacitor/ceramic/mlcc/info?part_no=C1608X5R1E106M080AC" (at 139.7 110.49 0)
      (effects (font (size 1.27 1.27) (thickness 0.15)) (justify left bottom) hide)
    )
    (property "Manufacturer" "TDK" (at 144.78 110.49 0)
      (effects (font (size 1.27 1.27) (thickness 0.15)) (justify left bottom) hide)
    )
    (property "MPN" "C1608X5R1E106M080AC" (at 142.24 110.49 0)
      (effects (font (size 1.27 1.27) (thickness 0.15)) (justify left bottom) hide)
    )
    (property "Val" "10u" (at 125.095 130.81 90)
      (effects (font (size 1.27 1.27) (thickness 0.15)) (justify right))
    )
    (property "License" "Apache-2.0" (at 147.32 110.49 0)
      (effects (font (size 1.27 1.27) (thickness 0.15)) (justify left bottom) hide)
    )
    (property "Author" "Antmicro" (at 149.86 110.49 0)
      (effects (font (size 1.27 1.27) (thickness 0.15)) (justify left bottom) hide)
    )
    (property "Voltage" "25V" (at 152.4 110.49 0)
      (effects (font (size 1.27 1.27)) (justify left bottom) hide)
    )
    (property "Dielectric" "" (at 154.94 110.49 0)
      (effects (font (size 1.27 1.27)) (justify left bottom) hide)
    )
    (pin "1")
    (pin "2")
    (instances
      (project "d1600e-psu-breakout-board"
        (path ""
          (reference "C24") (unit 1)
        )
      )
    )
  )

  (symbol (lib_id "antmicroDCDCConverters:AP62301_TSOT") (at 133.35 167.64 0) (unit 1)
    (in_bom yes) (on_board yes) (dnp no) (fields_autoplaced)
    (property "Reference" "U4" (at 143.51 160.02 0)
      (effects (font (size 1.27 1.27)))
    )
    (property "Value" "AP62301_TSOT" (at 168.91 175.26 0)
      (effects (font (size 1.27 1.27) (thickness 0.15)) (justify left bottom) hide)
    )
    (property "Footprint" "antmicro-footprints:TSOT23-6" (at 168.91 177.8 0)
      (effects (font (size 1.27 1.27) (thickness 0.15)) (justify left bottom) hide)
    )
    (property "Datasheet" "https://www.diodes.com/assets/Datasheets/AP62300_AP62301_AP62300T.pdf" (at 168.91 180.34 0)
      (effects (font (size 1.27 1.27) (thickness 0.15)) (justify left bottom) hide)
    )
    (property "MPN" "AP62301WU-7" (at 143.51 162.56 0)
      (effects (font (size 1.27 1.27) (thickness 0.15)))
    )
    (property "Manufacturer" "Diodes Incorporated" (at 168.91 182.88 0)
      (effects (font (size 1.27 1.27) (thickness 0.15)) (justify left bottom) hide)
    )
    (property "Author" "Antmicro" (at 168.91 185.42 0)
      (effects (font (size 1.27 1.27) (thickness 0.15)) (justify left bottom) hide)
    )
    (property "License" "Apache-2.0" (at 168.91 187.96 0)
      (effects (font (size 1.27 1.27) (thickness 0.15)) (justify left bottom) hide)
    )
    (pin "1")
    (pin "2")
    (pin "3")
    (pin "4")
    (pin "5")
    (pin "6")
    (instances
      (project "d1600e-psu-breakout-board"
        (path ""
          (reference "U4") (unit 1)
        )
      )
    )
  )

  (symbol (lib_id "antmicroFixedInductors:L_3u3_4.1A_WE-LHMI-5030") (at 168.91 167.64 0) (unit 1)
    (in_bom yes) (on_board yes) (dnp no) (fields_autoplaced)
    (property "Reference" "L1" (at 171.45 162.56 0)
      (effects (font (size 1.27 1.27)))
    )
    (property "Value" "L_3u3_4.1A_WE-LHMI-5030" (at 182.88 170.18 0)
      (effects (font (size 1.27 1.27) (thickness 0.15)) (justify left bottom) hide)
    )
    (property "Footprint" "antmicro-footprints:L_WE-LHMI-5030" (at 182.88 175.26 0)
      (effects (font (size 1.27 1.27) (thickness 0.15)) (justify left bottom) hide)
    )
    (property "Datasheet" "https://www.we-online.com/catalog/datasheet/74437336033.pdf" (at 182.88 177.8 0)
      (effects (font (size 1.27 1.27) (thickness 0.15)) (justify left bottom) hide)
    )
    (property "Manufacturer" "Würth Elektronik" (at 182.88 180.34 0)
      (effects (font (size 1.27 1.27) (thickness 0.15)) (justify left bottom) hide)
    )
    (property "MPN" "74437336033" (at 182.88 182.88 0)
      (effects (font (size 1.27 1.27) (thickness 0.15)) (justify left bottom) hide)
    )
    (property "Val" "3u3/4.1A" (at 171.45 165.1 0)
      (effects (font (size 1.27 1.27) (thickness 0.15)))
    )
    (property "Size" "5.2x5.2" (at 182.88 190.5 0)
      (effects (font (size 1.27 1.27) (thickness 0.15)) (justify left bottom) hide)
    )
    (property "ISat" "5.45A" (at 182.88 184.15 0)
      (effects (font (size 1.27 1.27)) (justify left) hide)
    )
    (property "IMax" "4.1A" (at 182.88 187.96 0)
      (effects (font (size 1.27 1.27) (thickness 0.15)) (justify left bottom) hide)
    )
    (property "Author" "Antmicro" (at 182.88 193.04 0)
      (effects (font (size 1.27 1.27) (thickness 0.15)) (justify left bottom) hide)
    )
    (property "License" "Apache-2.0" (at 182.88 195.58 0)
      (effects (font (size 1.27 1.27) (thickness 0.15)) (justify left bottom) hide)
    )
    (pin "1")
    (pin "2")
    (instances
      (project "d1600e-psu-breakout-board"
        (path ""
          (reference "L1") (unit 1)
        )
      )
    )
  )

  (symbol (lib_id "antmicroCapacitors0402:C_100n_0402") (at 156.21 172.72 0) (unit 1)
    (in_bom yes) (on_board yes) (dnp no)
    (property "Reference" "C34" (at 161.925 171.45 0)
      (effects (font (size 1.27 1.27)))
    )
    (property "Value" "C_100n_0402" (at 176.53 182.88 0)
      (effects (font (size 1.27 1.27) (thickness 0.15)) (justify left bottom) hide)
    )
    (property "Footprint" "antmicro-footprints:C_0402_1005Metric" (at 176.53 185.42 0)
      (effects (font (size 1.27 1.27) (thickness 0.15)) (justify left bottom) hide)
    )
    (property "Datasheet" "https://www.murata.com/products/productdetail?partno=GRM155R61H104KE14%23" (at 176.53 187.96 0)
      (effects (font (size 1.27 1.27) (thickness 0.15)) (justify left bottom) hide)
    )
    (property "Manufacturer" "Murata" (at 176.53 193.04 0)
      (effects (font (size 1.27 1.27) (thickness 0.15)) (justify left bottom) hide)
    )
    (property "MPN" "GRM155R61H104KE14D" (at 176.53 190.5 0)
      (effects (font (size 1.27 1.27) (thickness 0.15)) (justify left bottom) hide)
    )
    (property "Val" "100n" (at 162.56 173.99 0)
      (effects (font (size 1.27 1.27) (thickness 0.15)))
    )
    (property "License" "Apache-2.0" (at 176.53 195.58 0)
      (effects (font (size 1.27 1.27) (thickness 0.15)) (justify left bottom) hide)
    )
    (property "Author" "Antmicro" (at 176.53 198.12 0)
      (effects (font (size 1.27 1.27) (thickness 0.15)) (justify left bottom) hide)
    )
    (property "Voltage" "50V" (at 176.53 200.66 0)
      (effects (font (size 1.27 1.27)) (justify left bottom) hide)
    )
    (property "Dielectric" "X5R" (at 176.53 203.2 0)
      (effects (font (size 1.27 1.27)) (justify left bottom) hide)
    )
    (pin "1")
    (pin "2")
    (instances
      (project "d1600e-psu-breakout-board"
        (path ""
          (reference "C34") (unit 1)
        )
      )
    )
  )

  (symbol (lib_id "antmicropower:GND") (at 176.53 189.23 0) (unit 1)
    (in_bom yes) (on_board yes) (dnp no)
    (property "Reference" "#PWR081" (at 176.53 195.58 0)
      (effects (font (size 1.27 1.27)) hide)
    )
    (property "Value" "GND" (at 176.53 193.04 0)
      (effects (font (size 1.27 1.27) (thickness 0.15)))
    )
    (property "Footprint" "" (at 185.42 196.85 0)
      (effects (font (size 1.27 1.27) (thickness 0.15)) (justify left bottom) hide)
    )
    (property "Datasheet" "" (at 185.42 201.93 0)
      (effects (font (size 1.27 1.27) (thickness 0.15)) (justify left bottom) hide)
    )
    (property "Author" "Antmicro" (at 185.42 196.85 0)
      (effects (font (size 1.27 1.27) (thickness 0.15)) (justify left bottom) hide)
    )
    (property "License" "Apache-2.0" (at 185.42 199.39 0)
      (effects (font (size 1.27 1.27) (thickness 0.15)) (justify left bottom) hide)
    )
    (pin "1")
    (instances
      (project "d1600e-psu-breakout-board"
        (path ""
          (reference "#PWR081") (unit 1)
        )
      )
    )
  )

  (symbol (lib_id "antmicropower:GND") (at 132.08 189.23 0) (unit 1)
    (in_bom yes) (on_board yes) (dnp no)
    (property "Reference" "#PWR080" (at 132.08 195.58 0)
      (effects (font (size 1.27 1.27)) hide)
    )
    (property "Value" "GND" (at 132.08 193.04 0)
      (effects (font (size 1.27 1.27) (thickness 0.15)))
    )
    (property "Footprint" "" (at 140.97 196.85 0)
      (effects (font (size 1.27 1.27) (thickness 0.15)) (justify left bottom) hide)
    )
    (property "Datasheet" "" (at 140.97 201.93 0)
      (effects (font (size 1.27 1.27) (thickness 0.15)) (justify left bottom) hide)
    )
    (property "Author" "Antmicro" (at 140.97 196.85 0)
      (effects (font (size 1.27 1.27) (thickness 0.15)) (justify left bottom) hide)
    )
    (property "License" "Apache-2.0" (at 140.97 199.39 0)
      (effects (font (size 1.27 1.27) (thickness 0.15)) (justify left bottom) hide)
    )
    (pin "1")
    (instances
      (project "d1600e-psu-breakout-board"
        (path ""
          (reference "#PWR080") (unit 1)
        )
      )
    )
  )

  (symbol (lib_id "antmicroCapacitors0603:C_22u_0603") (at 185.42 181.61 90) (unit 1)
    (in_bom yes) (on_board yes) (dnp no)
    (property "Reference" "C35" (at 186.055 177.165 90)
      (effects (font (size 1.27 1.27)) (justify right))
    )
    (property "Value" "C_22u_0603" (at 195.58 161.29 0)
      (effects (font (size 1.27 1.27) (thickness 0.15)) (justify left bottom) hide)
    )
    (property "Footprint" "antmicro-footprints:C_0603_1608Metric" (at 198.12 161.29 0)
      (effects (font (size 1.27 1.27) (thickness 0.15)) (justify left bottom) hide)
    )
    (property "Datasheet" "https://www.murata.com/products/productdetail?partno=GRM188R60J226MEA0%23" (at 200.66 161.29 0)
      (effects (font (size 1.27 1.27) (thickness 0.15)) (justify left bottom) hide)
    )
    (property "Manufacturer" "Murata" (at 205.74 161.29 0)
      (effects (font (size 1.27 1.27) (thickness 0.15)) (justify left bottom) hide)
    )
    (property "MPN" "GRM188R60J226MEA0D" (at 203.2 161.29 0)
      (effects (font (size 1.27 1.27) (thickness 0.15)) (justify left bottom) hide)
    )
    (property "Val" "22u" (at 186.055 180.975 90)
      (effects (font (size 1.27 1.27) (thickness 0.15)) (justify right))
    )
    (property "License" "Apache-2.0" (at 208.28 161.29 0)
      (effects (font (size 1.27 1.27) (thickness 0.15)) (justify left bottom) hide)
    )
    (property "Author" "Antmicro" (at 210.82 161.29 0)
      (effects (font (size 1.27 1.27) (thickness 0.15)) (justify left bottom) hide)
    )
    (property "Voltage" "" (at 213.36 161.29 0)
      (effects (font (size 1.27 1.27)) (justify left bottom) hide)
    )
    (property "Dielectric" "" (at 215.9 161.29 0)
      (effects (font (size 1.27 1.27)) (justify left bottom) hide)
    )
    (pin "1")
    (pin "2")
    (instances
      (project "d1600e-psu-breakout-board"
        (path ""
          (reference "C35") (unit 1)
        )
      )
    )
  )

  (symbol (lib_id "antmicroCapacitors0603:C_22u_0603") (at 194.31 181.61 90) (unit 1)
    (in_bom yes) (on_board yes) (dnp no)
    (property "Reference" "C36" (at 194.945 177.165 90)
      (effects (font (size 1.27 1.27)) (justify right))
    )
    (property "Value" "C_22u_0603" (at 204.47 161.29 0)
      (effects (font (size 1.27 1.27) (thickness 0.15)) (justify left bottom) hide)
    )
    (property "Footprint" "antmicro-footprints:C_0603_1608Metric" (at 207.01 161.29 0)
      (effects (font (size 1.27 1.27) (thickness 0.15)) (justify left bottom) hide)
    )
    (property "Datasheet" "https://www.murata.com/products/productdetail?partno=GRM188R60J226MEA0%23" (at 209.55 161.29 0)
      (effects (font (size 1.27 1.27) (thickness 0.15)) (justify left bottom) hide)
    )
    (property "Manufacturer" "Murata" (at 214.63 161.29 0)
      (effects (font (size 1.27 1.27) (thickness 0.15)) (justify left bottom) hide)
    )
    (property "MPN" "GRM188R60J226MEA0D" (at 212.09 161.29 0)
      (effects (font (size 1.27 1.27) (thickness 0.15)) (justify left bottom) hide)
    )
    (property "Val" "22u" (at 194.945 180.975 90)
      (effects (font (size 1.27 1.27) (thickness 0.15)) (justify right))
    )
    (property "License" "Apache-2.0" (at 217.17 161.29 0)
      (effects (font (size 1.27 1.27) (thickness 0.15)) (justify left bottom) hide)
    )
    (property "Author" "Antmicro" (at 219.71 161.29 0)
      (effects (font (size 1.27 1.27) (thickness 0.15)) (justify left bottom) hide)
    )
    (property "Voltage" "" (at 222.25 161.29 0)
      (effects (font (size 1.27 1.27)) (justify left bottom) hide)
    )
    (property "Dielectric" "" (at 224.79 161.29 0)
      (effects (font (size 1.27 1.27)) (justify left bottom) hide)
    )
    (pin "1")
    (pin "2")
    (instances
      (project "d1600e-psu-breakout-board"
        (path ""
          (reference "C36") (unit 1)
        )
      )
    )
  )

  (symbol (lib_id "antmicropower:GND") (at 124.46 189.23 0) (unit 1)
    (in_bom yes) (on_board yes) (dnp no)
    (property "Reference" "#PWR079" (at 124.46 195.58 0)
      (effects (font (size 1.27 1.27)) hide)
    )
    (property "Value" "GND" (at 124.46 193.04 0)
      (effects (font (size 1.27 1.27) (thickness 0.15)))
    )
    (property "Footprint" "" (at 133.35 196.85 0)
      (effects (font (size 1.27 1.27) (thickness 0.15)) (justify left bottom) hide)
    )
    (property "Datasheet" "" (at 133.35 201.93 0)
      (effects (font (size 1.27 1.27) (thickness 0.15)) (justify left bottom) hide)
    )
    (property "Author" "Antmicro" (at 133.35 196.85 0)
      (effects (font (size 1.27 1.27) (thickness 0.15)) (justify left bottom) hide)
    )
    (property "License" "Apache-2.0" (at 133.35 199.39 0)
      (effects (font (size 1.27 1.27) (thickness 0.15)) (justify left bottom) hide)
    )
    (pin "1")
    (instances
      (project "d1600e-psu-breakout-board"
        (path ""
          (reference "#PWR079") (unit 1)
        )
      )
    )
  )

  (symbol (lib_id "antmicropower:GND") (at 185.42 189.23 0) (unit 1)
    (in_bom yes) (on_board yes) (dnp no)
    (property "Reference" "#PWR082" (at 185.42 195.58 0)
      (effects (font (size 1.27 1.27)) hide)
    )
    (property "Value" "GND" (at 185.42 193.04 0)
      (effects (font (size 1.27 1.27) (thickness 0.15)))
    )
    (property "Footprint" "" (at 194.31 196.85 0)
      (effects (font (size 1.27 1.27) (thickness 0.15)) (justify left bottom) hide)
    )
    (property "Datasheet" "" (at 194.31 201.93 0)
      (effects (font (size 1.27 1.27) (thickness 0.15)) (justify left bottom) hide)
    )
    (property "Author" "Antmicro" (at 194.31 196.85 0)
      (effects (font (size 1.27 1.27) (thickness 0.15)) (justify left bottom) hide)
    )
    (property "License" "Apache-2.0" (at 194.31 199.39 0)
      (effects (font (size 1.27 1.27) (thickness 0.15)) (justify left bottom) hide)
    )
    (pin "1")
    (instances
      (project "d1600e-psu-breakout-board"
        (path ""
          (reference "#PWR082") (unit 1)
        )
      )
    )
  )

  (symbol (lib_id "antmicropower:GND") (at 194.31 189.23 0) (unit 1)
    (in_bom yes) (on_board yes) (dnp no)
    (property "Reference" "#PWR083" (at 194.31 195.58 0)
      (effects (font (size 1.27 1.27)) hide)
    )
    (property "Value" "GND" (at 194.31 193.04 0)
      (effects (font (size 1.27 1.27) (thickness 0.15)))
    )
    (property "Footprint" "" (at 203.2 196.85 0)
      (effects (font (size 1.27 1.27) (thickness 0.15)) (justify left bottom) hide)
    )
    (property "Datasheet" "" (at 203.2 201.93 0)
      (effects (font (size 1.27 1.27) (thickness 0.15)) (justify left bottom) hide)
    )
    (property "Author" "Antmicro" (at 203.2 196.85 0)
      (effects (font (size 1.27 1.27) (thickness 0.15)) (justify left bottom) hide)
    )
    (property "License" "Apache-2.0" (at 203.2 199.39 0)
      (effects (font (size 1.27 1.27) (thickness 0.15)) (justify left bottom) hide)
    )
    (pin "1")
    (instances
      (project "d1600e-psu-breakout-board"
        (path ""
          (reference "#PWR083") (unit 1)
        )
      )
    )
  )

  (symbol (lib_id "antmicroCapacitors0603:C_10u_25V_0603") (at 124.46 181.61 90) (unit 1)
    (in_bom yes) (on_board yes) (dnp no)
    (property "Reference" "C33" (at 125.095 177.165 90)
      (effects (font (size 1.27 1.27)) (justify right))
    )
    (property "Value" "C_10u_25V_0603" (at 134.62 161.29 0)
      (effects (font (size 1.27 1.27) (thickness 0.15)) (justify left bottom) hide)
    )
    (property "Footprint" "antmicro-footprints:C_0603_1608Metric" (at 137.16 161.29 0)
      (effects (font (size 1.27 1.27) (thickness 0.15)) (justify left bottom) hide)
    )
    (property "Datasheet" "https://product.tdk.com/en/search/capacitor/ceramic/mlcc/info?part_no=C1608X5R1E106M080AC" (at 139.7 161.29 0)
      (effects (font (size 1.27 1.27) (thickness 0.15)) (justify left bottom) hide)
    )
    (property "Manufacturer" "TDK" (at 144.78 161.29 0)
      (effects (font (size 1.27 1.27) (thickness 0.15)) (justify left bottom) hide)
    )
    (property "MPN" "C1608X5R1E106M080AC" (at 142.24 161.29 0)
      (effects (font (size 1.27 1.27) (thickness 0.15)) (justify left bottom) hide)
    )
    (property "Val" "10u" (at 125.095 180.975 90)
      (effects (font (size 1.27 1.27) (thickness 0.15)) (justify right))
    )
    (property "License" "Apache-2.0" (at 147.32 161.29 0)
      (effects (font (size 1.27 1.27) (thickness 0.15)) (justify left bottom) hide)
    )
    (property "Author" "Antmicro" (at 149.86 161.29 0)
      (effects (font (size 1.27 1.27) (thickness 0.15)) (justify left bottom) hide)
    )
    (property "Voltage" "25V" (at 152.4 161.29 0)
      (effects (font (size 1.27 1.27)) (justify left bottom) hide)
    )
    (property "Dielectric" "" (at 154.94 161.29 0)
      (effects (font (size 1.27 1.27)) (justify left bottom) hide)
    )
    (pin "1")
    (pin "2")
    (instances
      (project "d1600e-psu-breakout-board"
        (path ""
          (reference "C33") (unit 1)
        )
      )
    )
  )

  (symbol (lib_id "antmicropower:GND") (at 297.18 165.1 0) (unit 1)
    (in_bom yes) (on_board yes) (dnp no)
    (property "Reference" "#PWR0135" (at 297.18 171.45 0)
      (effects (font (size 1.27 1.27)) hide)
    )
    (property "Value" "GND" (at 297.18 168.91 0)
      (effects (font (size 1.27 1.27) (thickness 0.15)))
    )
    (property "Footprint" "" (at 306.07 172.72 0)
      (effects (font (size 1.27 1.27) (thickness 0.15)) (justify left bottom) hide)
    )
    (property "Datasheet" "" (at 306.07 177.8 0)
      (effects (font (size 1.27 1.27) (thickness 0.15)) (justify left bottom) hide)
    )
    (property "Author" "Antmicro" (at 306.07 172.72 0)
      (effects (font (size 1.27 1.27) (thickness 0.15)) (justify left bottom) hide)
    )
    (property "License" "Apache-2.0" (at 306.07 175.26 0)
      (effects (font (size 1.27 1.27) (thickness 0.15)) (justify left bottom) hide)
    )
    (pin "1")
    (instances
      (project "d1600e-psu-breakout-board"
        (path ""
          (reference "#PWR0135") (unit 1)
        )
      )
    )
  )

  (symbol (lib_id "antmicroWire2BoardConnectors:Molex_Mini-Fit-Jr_2x5_39-28-1103") (at 275.59 148.59 0) (mirror y) (unit 1)
    (in_bom yes) (on_board yes) (dnp no) (fields_autoplaced)
    (property "Reference" "J9" (at 269.24 142.24 0)
      (effects (font (size 1.27 1.27) (thickness 0.15)))
    )
    (property "Value" "Molex_Mini-Fit-Jr_2x5_39-28-1103" (at 250.19 158.75 0)
      (effects (font (size 1.27 1.27) (thickness 0.15)) (justify left bottom) hide)
    )
    (property "Footprint" "antmicro-footprints:MOLEX_39281103" (at 250.19 161.29 0)
      (effects (font (size 1.27 1.27) (thickness 0.15)) (justify left bottom) hide)
    )
    (property "Datasheet" "https://www.molex.com/pdm_docs/sd/039281103_sd.pdf" (at 250.19 163.83 0)
      (effects (font (size 1.27 1.27) (thickness 0.15)) (justify left bottom) hide)
    )
    (property "MPN" "39-28-1103" (at 269.24 144.78 0)
      (effects (font (size 1.27 1.27) (thickness 0.15)))
    )
    (property "Manufacturer" "Molex" (at 250.19 166.37 0)
      (effects (font (size 1.27 1.27) (thickness 0.15)) (justify left bottom) hide)
    )
    (property "Author" "Antmicro" (at 250.19 168.91 0)
      (effects (font (size 1.27 1.27) (thickness 0.15)) (justify left bottom) hide)
    )
    (property "License" "Apache-2.0" (at 250.19 171.45 0)
      (effects (font (size 1.27 1.27) (thickness 0.15)) (justify left bottom) hide)
    )
    (pin "4")
    (pin "3")
    (pin "9")
    (pin "7")
    (pin "10")
    (pin "1")
    (pin "5")
    (pin "6")
    (pin "8")
    (pin "2")
    (instances
      (project "d1600e-psu-breakout-board"
        (path ""
          (reference "J9") (unit 1)
        )
      )
    )
  )

  (symbol (lib_id "antmicroGenericPinHeaders:PinHeader_1x3_P2.54mm_Drill1.1mm") (at 298.45 151.13 0) (unit 1)
    (in_bom yes) (on_board yes) (dnp no)
    (property "Reference" "SW1" (at 300.99 144.78 0)
      (effects (font (size 1.27 1.27)) (justify left))
    )
    (property "Value" "PinHeader_1x3_P2.54mm_Drill1.1mm" (at 318.77 161.29 0)
      (effects (font (size 1.27 1.27) (thickness 0.15)) (justify left bottom) hide)
    )
    (property "Footprint" "antmicro-footprints:PinHeader_1x3_P2.54mm_Drill1.1mm" (at 318.77 163.83 0)
      (effects (font (size 1.27 1.27) (thickness 0.15)) (justify left bottom) hide)
    )
    (property "Datasheet" "https://katalog.we-online.de/em/datasheet/6130xx11121.pdf" (at 318.77 166.37 0)
      (effects (font (size 1.27 1.27) (thickness 0.15)) (justify left bottom) hide)
    )
    (property "MPN" "61300311121" (at 300.99 147.32 0)
      (effects (font (size 1.27 1.27) (thickness 0.15)) (justify left))
    )
    (property "Manufacturer" "Würth Elektronik" (at 318.77 168.91 0)
      (effects (font (size 1.27 1.27) (thickness 0.15)) (justify left bottom) hide)
    )
    (property "Author" "Antmicro" (at 318.77 171.45 0)
      (effects (font (size 1.27 1.27) (thickness 0.15)) (justify left bottom) hide)
    )
    (property "License" "Apache-2.0" (at 318.77 173.99 0)
      (effects (font (size 1.27 1.27) (thickness 0.15)) (justify left bottom) hide)
    )
    (pin "1")
    (pin "2")
    (pin "3")
    (instances
      (project "d1600e-psu-breakout-board"
        (path ""
          (reference "SW1") (unit 1)
        )
      )
    )
  )

  (symbol (lib_id "antmicroResistors0402:R_680R_0402") (at 176.53 181.61 270) (unit 1)
    (in_bom yes) (on_board yes) (dnp no)
    (property "Reference" "R44" (at 177.8 182.88 90)
      (effects (font (size 1.27 1.27)) (justify left))
    )
    (property "Value" "R_680R_0402" (at 163.83 201.93 0)
      (effects (font (size 1.27 1.27) (thickness 0.15)) (justify left bottom) hide)
    )
    (property "Footprint" "antmicro-footprints:R_0402_1005Metric" (at 161.29 201.93 0)
      (effects (font (size 1.27 1.27) (thickness 0.15)) (justify left bottom) hide)
    )
    (property "Datasheet" "https://www.bourns.com/docs/product-datasheets/cr.pdf" (at 158.75 201.93 0)
      (effects (font (size 1.27 1.27) (thickness 0.15)) (justify left bottom) hide)
    )
    (property "Manufacturer" "Bourns" (at 153.67 201.93 0)
      (effects (font (size 1.27 1.27) (thickness 0.15)) (justify left bottom) hide)
    )
    (property "MPN" "CR0402-FX-6800GLF" (at 156.21 201.93 0)
      (effects (font (size 1.27 1.27) (thickness 0.15)) (justify left bottom) hide)
    )
    (property "Val" "680R" (at 177.8 185.42 90)
      (effects (font (size 1.27 1.27) (thickness 0.15)) (justify left))
    )
    (property "License" "Apache-2.0" (at 151.13 201.93 0)
      (effects (font (size 1.27 1.27) (thickness 0.15)) (justify left bottom) hide)
    )
    (property "Author" "Antmicro" (at 148.59 201.93 0)
      (effects (font (size 1.27 1.27) (thickness 0.15)) (justify left bottom) hide)
    )
    (property "Tolerance" "1%" (at 166.37 201.93 0)
      (effects (font (size 1.27 1.27)) (justify left bottom) hide)
    )
    (pin "1")
    (pin "2")
    (instances
      (project "d1600e-psu-breakout-board"
        (path ""
          (reference "R44") (unit 1)
        )
      )
    )
  )

  (symbol (lib_id "antmicroResistors0402:R_6k8_0402") (at 176.53 119.38 270) (unit 1)
    (in_bom yes) (on_board yes) (dnp no)
    (property "Reference" "R34" (at 177.8 120.65 90)
      (effects (font (size 1.27 1.27)) (justify left))
    )
    (property "Value" "R_6k8_0402" (at 163.83 139.7 0)
      (effects (font (size 1.27 1.27) (thickness 0.15)) (justify left bottom) hide)
    )
    (property "Footprint" "antmicro-footprints:R_0402_1005Metric" (at 161.29 139.7 0)
      (effects (font (size 1.27 1.27) (thickness 0.15)) (justify left bottom) hide)
    )
    (property "Datasheet" "https://www.bourns.com/docs/product-datasheets/cr.pdf" (at 158.75 139.7 0)
      (effects (font (size 1.27 1.27) (thickness 0.15)) (justify left bottom) hide)
    )
    (property "Manufacturer" "Bourns" (at 153.67 139.7 0)
      (effects (font (size 1.27 1.27) (thickness 0.15)) (justify left bottom) hide)
    )
    (property "MPN" "CR0402-FX-6801GLF" (at 156.21 139.7 0)
      (effects (font (size 1.27 1.27) (thickness 0.15)) (justify left bottom) hide)
    )
    (property "Val" "6k8" (at 177.8 123.19 90)
      (effects (font (size 1.27 1.27) (thickness 0.15)) (justify left))
    )
    (property "License" "Apache-2.0" (at 151.13 139.7 0)
      (effects (font (size 1.27 1.27) (thickness 0.15)) (justify left bottom) hide)
    )
    (property "Author" "Antmicro" (at 148.59 139.7 0)
      (effects (font (size 1.27 1.27) (thickness 0.15)) (justify left bottom) hide)
    )
    (property "Tolerance" "1%" (at 166.37 139.7 0)
      (effects (font (size 1.27 1.27)) (justify left bottom) hide)
    )
    (pin "1")
    (pin "2")
    (instances
      (project "d1600e-psu-breakout-board"
        (path ""
          (reference "R34") (unit 1)
        )
      )
    )
  )

  (symbol (lib_id "antmicropower:GND") (at 284.48 165.1 0) (unit 1)
    (in_bom yes) (on_board yes) (dnp no)
    (property "Reference" "#PWR0108" (at 284.48 171.45 0)
      (effects (font (size 1.27 1.27)) hide)
    )
    (property "Value" "GND" (at 284.48 168.91 0)
      (effects (font (size 1.27 1.27) (thickness 0.15)))
    )
    (property "Footprint" "" (at 293.37 172.72 0)
      (effects (font (size 1.27 1.27) (thickness 0.15)) (justify left bottom) hide)
    )
    (property "Datasheet" "" (at 293.37 177.8 0)
      (effects (font (size 1.27 1.27) (thickness 0.15)) (justify left bottom) hide)
    )
    (property "Author" "Antmicro" (at 293.37 172.72 0)
      (effects (font (size 1.27 1.27) (thickness 0.15)) (justify left bottom) hide)
    )
    (property "License" "Apache-2.0" (at 293.37 175.26 0)
      (effects (font (size 1.27 1.27) (thickness 0.15)) (justify left bottom) hide)
    )
    (pin "1")
    (instances
      (project "d1600e-psu-breakout-board"
        (path ""
          (reference "#PWR0108") (unit 1)
        )
      )
    )
  )

  (symbol (lib_id "antmicropower:GND") (at 259.08 165.1 0) (unit 1)
    (in_bom yes) (on_board yes) (dnp no)
    (property "Reference" "#PWR0104" (at 259.08 171.45 0)
      (effects (font (size 1.27 1.27)) hide)
    )
    (property "Value" "GND" (at 259.08 168.91 0)
      (effects (font (size 1.27 1.27) (thickness 0.15)))
    )
    (property "Footprint" "" (at 267.97 172.72 0)
      (effects (font (size 1.27 1.27) (thickness 0.15)) (justify left bottom) hide)
    )
    (property "Datasheet" "" (at 267.97 177.8 0)
      (effects (font (size 1.27 1.27) (thickness 0.15)) (justify left bottom) hide)
    )
    (property "Author" "Antmicro" (at 267.97 172.72 0)
      (effects (font (size 1.27 1.27) (thickness 0.15)) (justify left bottom) hide)
    )
    (property "License" "Apache-2.0" (at 267.97 175.26 0)
      (effects (font (size 1.27 1.27) (thickness 0.15)) (justify left bottom) hide)
    )
    (pin "1")
    (instances
      (project "d1600e-psu-breakout-board"
        (path ""
          (reference "#PWR0104") (unit 1)
        )
      )
    )
  )

  (symbol (lib_id "antmicroTestPoints:TP_1mm_SMD") (at 289.56 156.21 270) (unit 1)
    (in_bom no) (on_board yes) (dnp no)
    (property "Reference" "TP5" (at 289.56 161.29 90)
      (effects (font (size 1.27 1.27)))
    )
    (property "Value" "TP_1mm_SMD" (at 281.94 171.45 0)
      (effects (font (size 1.27 1.27) (thickness 0.15)) (justify left bottom) hide)
    )
    (property "Footprint" "antmicro-footprints:TP_SMD_1mm" (at 279.4 171.45 0)
      (effects (font (size 1.27 1.27) (thickness 0.15)) (justify left bottom) hide)
    )
    (property "Datasheet" "" (at 276.86 173.99 0)
      (effects (font (size 1.27 1.27) (thickness 0.15)) (justify left bottom) hide)
    )
    (property "MPN" "" (at 289.56 156.21 0)
      (effects (font (size 1.27 1.27)) hide)
    )
    (property "Manufacturer" "" (at 289.56 156.21 0)
      (effects (font (size 1.27 1.27)) hide)
    )
    (property "Author" "Antmicro" (at 274.32 171.45 0)
      (effects (font (size 1.27 1.27) (thickness 0.15)) (justify left bottom) hide)
    )
    (property "License" "Apache-2.0" (at 271.78 171.45 0)
      (effects (font (size 1.27 1.27) (thickness 0.15)) (justify left bottom) hide)
    )
    (pin "1")
    (instances
      (project "d1600e-psu-breakout-board"
        (path ""
          (reference "TP5") (unit 1)
        )
      )
    )
  )

  (symbol (lib_id "antmicroResistors0402:R_2k15_0402") (at 176.53 175.26 90) (unit 1)
    (in_bom yes) (on_board yes) (dnp no)
    (property "Reference" "R43" (at 177.8 171.45 90)
      (effects (font (size 1.27 1.27)) (justify right))
    )
    (property "Value" "R_2k15_0402" (at 186.69 160.02 0)
      (effects (font (size 1.27 1.27) (thickness 0.15)) (justify left bottom) hide)
    )
    (property "Footprint" "antmicro-footprints:R_0402_1005Metric" (at 189.23 160.02 0)
      (effects (font (size 1.27 1.27) (thickness 0.15)) (justify left bottom) hide)
    )
    (property "Datasheet" "https://www.mouser.com/datasheet/2/54/cr-1858361.pdf" (at 191.77 160.02 0)
      (effects (font (size 1.27 1.27) (thickness 0.15)) (justify left bottom) hide)
    )
    (property "Manufacturer" "Bourns" (at 199.39 160.02 0)
      (effects (font (size 1.27 1.27) (thickness 0.15)) (justify left bottom) hide)
    )
    (property "MPN" "CR0402-FX-2151GLF" (at 194.31 160.02 0)
      (effects (font (size 1.27 1.27) (thickness 0.15)) (justify left bottom) hide)
    )
    (property "Val" "2k15" (at 177.8 173.99 90)
      (effects (font (size 1.27 1.27) (thickness 0.15)) (justify right))
    )
    (property "Tolerance" "1%" (at 196.85 160.02 0)
      (effects (font (size 1.27 1.27) (thickness 0.15)) (justify left bottom) hide)
    )
    (property "Author" "Antmicro" (at 201.93 160.02 0)
      (effects (font (size 1.27 1.27) (thickness 0.15)) (justify left bottom) hide)
    )
    (property "License" "Apache-2.0" (at 204.47 160.02 0)
      (effects (font (size 1.27 1.27) (thickness 0.15)) (justify left bottom) hide)
    )
    (pin "1")
    (pin "2")
    (instances
      (project "d1600e-psu-breakout-board"
        (path ""
          (reference "R43") (unit 1)
        )
      )
    )
  )

  (symbol (lib_id "antmicroResistors0402:R_1k3_0402") (at 176.53 130.81 270) (unit 1)
    (in_bom yes) (on_board yes) (dnp no)
    (property "Reference" "R35" (at 177.8 132.08 90)
      (effects (font (size 1.27 1.27)) (justify left))
    )
    (property "Value" "R_1k3_0402" (at 163.83 151.13 0)
      (effects (font (size 1.27 1.27) (thickness 0.15)) (justify left bottom) hide)
    )
    (property "Footprint" "antmicro-footprints:R_0402_1005Metric" (at 161.29 151.13 0)
      (effects (font (size 1.27 1.27) (thickness 0.15)) (justify left bottom) hide)
    )
    (property "Datasheet" "https://www.bourns.com/docs/product-datasheets/cr.pdf" (at 158.75 151.13 0)
      (effects (font (size 1.27 1.27) (thickness 0.15)) (justify left bottom) hide)
    )
    (property "Manufacturer" "Bourns" (at 153.67 151.13 0)
      (effects (font (size 1.27 1.27) (thickness 0.15)) (justify left bottom) hide)
    )
    (property "MPN" "CR0402-FX-1301GLF" (at 156.21 151.13 0)
      (effects (font (size 1.27 1.27) (thickness 0.15)) (justify left bottom) hide)
    )
    (property "Val" "1k3" (at 177.8 134.62 90)
      (effects (font (size 1.27 1.27) (thickness 0.15)) (justify left))
    )
    (property "License" "Apache-2.0" (at 151.13 151.13 0)
      (effects (font (size 1.27 1.27) (thickness 0.15)) (justify left bottom) hide)
    )
    (property "Author" "Antmicro" (at 148.59 151.13 0)
      (effects (font (size 1.27 1.27) (thickness 0.15)) (justify left bottom) hide)
    )
    (property "Tolerance" "1%" (at 166.37 151.13 0)
      (effects (font (size 1.27 1.27)) (justify left bottom) hide)
    )
    (pin "1")
    (pin "2")
    (instances
      (project "d1600e-psu-breakout-board"
        (path ""
          (reference "R35") (unit 1)
        )
      )
    )
  )
)
